(kicad_pcb
	(version 20260206)
	(generator "pcbnew")
	(generator_version "10.0")
	(general
		(thickness 1.6)
		(legacy_teardrops no)
	)
	(paper "A4")
	(title_block
		(title "Bryce Canyon_IOM_IOC_16318-2_OCP.brd")
		(comment 1 "Bryce Canyon / footprints 1226-1232 of 1605")
	)
	(layers
		(0 "F.Cu" signal "TOP")
		(4 "In1.Cu" signal "L2GND")
		(6 "In2.Cu" signal "L3")
		(8 "In3.Cu" signal "L4VCC")
		(10 "In4.Cu" signal "L5VCC")
		(12 "In5.Cu" signal "L6")
		(14 "In6.Cu" signal "L7GND")
		(2 "B.Cu" signal "BOTTOM")
		(9 "F.Adhes" user "F.Adhesive")
		(11 "B.Adhes" user "B.Adhesive")
		(13 "F.Paste" user "Package Geometry/Pastemask Top")
		(15 "B.Paste" user "Package Geometry/Pastemask Bottom")
		(5 "F.SilkS" user "Ref Des/Silkscreen Top")
		(7 "B.SilkS" user "Ref Des/Silkscreen Bottom")
		(1 "F.Mask" user "Board Geometry/Soldermask Top")
		(3 "B.Mask" user "Board Geometry/Soldermask Bottom")
		(17 "Dwgs.User" user "User.Drawings")
		(19 "Cmts.User" user "User.Comments")
		(21 "Eco1.User" user "User.Eco1")
		(23 "Eco2.User" user "User.Eco2")
		(25 "Edge.Cuts" user "Board Geometry/Outline")
		(27 "Margin" user)
		(31 "F.CrtYd" user "Package Geometry/Place Bound Top")
		(29 "B.CrtYd" user "Package Geometry/Place Bound Bottom")
		(35 "F.Fab" user "Ref Des/Assembly Top")
		(33 "B.Fab" user "Ref Des/Assembly Bottom")
	)
	(footprint ""
		(layer "B.Cu")
		(at 85.415628 -99.121722 180)
		(property "Reference" "Q25"
			(at 0 0 0)
			(layer "B.SilkS")
			(hide yes)
			(effects
				(font
					(size 1.27 1.27)
				)
				(justify mirror)
			)
		)
		(property "Value" "2N7002K-1-GP"
			(at -0.127 -8.9662 180)
			(unlocked yes)
			(layer "B.Fab")
			(hide yes)
			(effects
				(font
					(size 1.016 1.016)
					(thickness 0.1524)
				)
				(justify mirror)
			)
		)
		(property "Device Type" "SOT23DGS2D4H44"
			(at -0.127 -10.4902 180)
			(unlocked yes)
			(layer "B.Fab")
			(hide yes)
			(effects
				(font
					(size 1.016 1.016)
					(thickness 0.1524)
				)
				(justify mirror)
			)
		)
		(duplicate_pad_numbers_are_jumpers no)
		(fp_line
			(start 1.651 1.778)
			(end -1.651 1.778)
			(stroke
				(width 0.1524)
				(type default)
			)
			(layer "B.SilkS")
		)
		(fp_line
			(start 1.651 -1.778)
			(end 1.651 1.778)
			(stroke
				(width 0.1524)
				(type default)
			)
			(layer "B.SilkS")
		)
		(fp_line
			(start -1.651 1.778)
			(end -1.651 -1.778)
			(stroke
				(width 0.1524)
				(type default)
			)
			(layer "B.SilkS")
		)
		(fp_line
			(start -1.651 -1.778)
			(end 1.651 -1.778)
			(stroke
				(width 0.1524)
				(type default)
			)
			(layer "B.SilkS")
		)
		(fp_poly
			(pts
				(xy 1.778 1.8796) (xy 1.778 -1.8796) (xy -1.778 -1.8796) (xy -1.778 1.8796)
			)
			(stroke
				(width 0)
				(type default)
			)
			(fill no)
			(layer "B.CrtYd")
		)
		(fp_poly
			(pts
				(xy 1.778 1.8796) (xy 1.778 -1.8796) (xy -1.778 -1.8796) (xy -1.778 1.8796)
			)
			(stroke
				(width 0)
				(type default)
			)
			(fill no)
			(layer "B.Fab")
		)
		(pad "D" smd custom
			(at 0 -0.9525)
			(size 0.1905 0.1905)
			(layers "B.Cu" "B.Mask" "B.Paste")
			(net "CONN_A_PRSNTA")
			(options
				(clearance outline)
				(anchor circle)
			)
			(primitives
				(gr_poly
					(pts
						(arc
							(start -0.1778 -0.5715)
							(mid -0.321484 -0.511984)
							(end -0.381 -0.3683)
						)
						(arc
							(start -0.381 0.3683)
							(mid -0.321484 0.511984)
							(end -0.1778 0.5715)
						)
						(arc
							(start 0.1778 0.5715)
							(mid 0.321484 0.511984)
							(end 0.381 0.3683)
						)
						(arc
							(start 0.381 -0.3683)
							(mid 0.321484 -0.511984)
							(end 0.1778 -0.5715)
						)
					)
					(width 0)
					(fill yes)
				)
			)
		)
		(pad "G" smd custom
			(at 0.98425 0.9525)
			(size 0.1905 0.1905)
			(layers "B.Cu" "B.Mask" "B.Paste")
			(net "MEZZ_A_PRSNT_120_N")
			(options
				(clearance outline)
				(anchor circle)
			)
			(primitives
				(gr_poly
					(pts
						(arc
							(start -0.1778 -0.5715)
							(mid -0.321484 -0.511984)
							(end -0.381 -0.3683)
						)
						(arc
							(start -0.381 0.3683)
							(mid -0.321484 0.511984)
							(end -0.1778 0.5715)
						)
						(arc
							(start 0.1778 0.5715)
							(mid 0.321484 0.511984)
							(end 0.381 0.3683)
						)
						(arc
							(start 0.381 -0.3683)
							(mid 0.321484 -0.511984)
							(end 0.1778 -0.5715)
						)
					)
					(width 0)
					(fill yes)
				)
			)
		)
		(pad "S" smd custom
			(at -0.98425 0.9525)
			(size 0.1905 0.1905)
			(layers "B.Cu" "B.Mask" "B.Paste")
			(net "GND")
			(options
				(clearance outline)
				(anchor circle)
			)
			(primitives
				(gr_poly
					(pts
						(arc
							(start -0.1778 -0.5715)
							(mid -0.321484 -0.511984)
							(end -0.381 -0.3683)
						)
						(arc
							(start -0.381 0.3683)
							(mid -0.321484 0.511984)
							(end -0.1778 0.5715)
						)
						(arc
							(start 0.1778 0.5715)
							(mid 0.321484 0.511984)
							(end 0.381 0.3683)
						)
						(arc
							(start 0.381 -0.3683)
							(mid 0.321484 -0.511984)
							(end 0.1778 -0.5715)
						)
					)
					(width 0)
					(fill yes)
				)
			)
		)
	)
	(footprint ""
		(layer "B.Cu")
		(at 119.4562 -15.6972 90)
		(property "Reference" "Q20"
			(at 0 0 90)
			(layer "B.SilkS")
			(hide yes)
			(effects
				(font
					(size 1.27 1.27)
				)
				(justify mirror)
			)
		)
		(property "Value" "2N7002K-1-GP"
			(at -0.127 -8.9662 90)
			(unlocked yes)
			(layer "B.Fab")
			(hide yes)
			(effects
				(font
					(size 1.016 1.016)
					(thickness 0.1524)
				)
				(justify mirror)
			)
		)
		(property "Device Type" "SOT23DGS2D4H44"
			(at -0.127 -10.4902 90)
			(unlocked yes)
			(layer "B.Fab")
			(hide yes)
			(effects
				(font
					(size 1.016 1.016)
					(thickness 0.1524)
				)
				(justify mirror)
			)
		)
		(duplicate_pad_numbers_are_jumpers no)
		(fp_line
			(start 1.651 -1.778)
			(end 1.651 1.778)
			(stroke
				(width 0.1524)
				(type default)
			)
			(layer "B.SilkS")
		)
		(fp_line
			(start -1.651 -1.778)
			(end 1.651 -1.778)
			(stroke
				(width 0.1524)
				(type default)
			)
			(layer "B.SilkS")
		)
		(fp_line
			(start 1.651 1.778)
			(end -1.651 1.778)
			(stroke
				(width 0.1524)
				(type default)
			)
			(layer "B.SilkS")
		)
		(fp_line
			(start -1.651 1.778)
			(end -1.651 -1.778)
			(stroke
				(width 0.1524)
				(type default)
			)
			(layer "B.SilkS")
		)
		(fp_poly
			(pts
				(xy 1.778 1.8796) (xy 1.778 -1.8796) (xy -1.778 -1.8796) (xy -1.778 1.8796)
			)
			(stroke
				(width 0)
				(type default)
			)
			(fill no)
			(layer "B.CrtYd")
		)
		(fp_poly
			(pts
				(xy 1.778 1.8796) (xy 1.778 -1.8796) (xy -1.778 -1.8796) (xy -1.778 1.8796)
			)
			(stroke
				(width 0)
				(type default)
			)
			(fill no)
			(layer "B.Fab")
		)
		(pad "D" smd custom
			(at 0 -0.9525 270)
			(size 0.1905 0.1905)
			(layers "B.Cu" "B.Mask" "B.Paste")
			(net "IOM_ADM1278_EN")
			(options
				(clearance outline)
				(anchor circle)
			)
			(primitives
				(gr_poly
					(pts
						(arc
							(start -0.1778 -0.5715)
							(mid -0.321484 -0.511984)
							(end -0.381 -0.3683)
						)
						(arc
							(start -0.381 0.3683)
							(mid -0.321484 0.511984)
							(end -0.1778 0.5715)
						)
						(arc
							(start 0.1778 0.5715)
							(mid 0.321484 0.511984)
							(end 0.381 0.3683)
						)
						(arc
							(start 0.381 -0.3683)
							(mid 0.321484 -0.511984)
							(end 0.1778 -0.5715)
						)
					)
					(width 0)
					(fill yes)
				)
			)
		)
		(pad "G" smd custom
			(at 0.98425 0.9525 270)
			(size 0.1905 0.1905)
			(layers "B.Cu" "B.Mask" "B.Paste")
			(net "IOM_MATED_N")
			(options
				(clearance outline)
				(anchor circle)
			)
			(primitives
				(gr_poly
					(pts
						(arc
							(start -0.1778 -0.5715)
							(mid -0.321484 -0.511984)
							(end -0.381 -0.3683)
						)
						(arc
							(start -0.381 0.3683)
							(mid -0.321484 0.511984)
							(end -0.1778 0.5715)
						)
						(arc
							(start 0.1778 0.5715)
							(mid 0.321484 0.511984)
							(end 0.381 0.3683)
						)
						(arc
							(start 0.381 -0.3683)
							(mid 0.321484 -0.511984)
							(end 0.1778 -0.5715)
						)
					)
					(width 0)
					(fill yes)
				)
			)
		)
		(pad "S" smd custom
			(at -0.98425 0.9525 270)
			(size 0.1905 0.1905)
			(layers "B.Cu" "B.Mask" "B.Paste")
			(net "GND")
			(options
				(clearance outline)
				(anchor circle)
			)
			(primitives
				(gr_poly
					(pts
						(arc
							(start -0.1778 -0.5715)
							(mid -0.321484 -0.511984)
							(end -0.381 -0.3683)
						)
						(arc
							(start -0.381 0.3683)
							(mid -0.321484 0.511984)
							(end -0.1778 0.5715)
						)
						(arc
							(start 0.1778 0.5715)
							(mid 0.321484 0.511984)
							(end 0.381 0.3683)
						)
						(arc
							(start 0.381 -0.3683)
							(mid 0.321484 -0.511984)
							(end 0.1778 -0.5715)
						)
					)
					(width 0)
					(fill yes)
				)
			)
		)
	)
	(footprint ""
		(layer "B.Cu")
		(at 192.4177 -63.2206 90)
		(property "Reference" "C418"
			(at 0 0 90)
			(layer "B.SilkS")
			(hide yes)
			(effects
				(font
					(size 1.27 1.27)
				)
				(justify mirror)
			)
		)
		(property "Value" "SCD1U6D3V1KX-GP"
			(at 2.8321 -1.7399 90)
			(unlocked yes)
			(layer "B.Fab")
			(hide yes)
			(effects
				(font
					(size 1.016 1.016)
					(thickness 0.1524)
				)
				(justify mirror)
			)
		)
		(property "Device Type" "C0201H13"
			(at 2.8321 -3.2639 90)
			(unlocked yes)
			(layer "B.Fab")
			(hide yes)
			(effects
				(font
					(size 1.016 1.016)
					(thickness 0.1524)
				)
				(justify mirror)
			)
		)
		(duplicate_pad_numbers_are_jumpers no)
		(fp_rect
			(start 0.2794 0.6477)
			(end -0.2794 -0.6477)
			(stroke
				(width 0)
				(type default)
			)
			(fill no)
			(layer "B.CrtYd")
		)
		(fp_rect
			(start 0.2794 0.6477)
			(end -0.2794 -0.6477)
			(stroke
				(width 0)
				(type default)
			)
			(fill no)
			(layer "B.Fab")
		)
		(pad "1" smd custom
			(at 0 -0.2794 270)
			(size 0.0762 0.0762)
			(layers "B.Cu" "B.Mask" "B.Paste")
			(net "P0V975")
			(options
				(clearance outline)
				(anchor circle)
			)
			(primitives
				(gr_poly
					(pts
						(arc
							(start 0.1524 0.127)
							(mid 0.137521 0.162921)
							(end 0.1016 0.1778)
						)
						(arc
							(start -0.1016 0.1778)
							(mid -0.137521 0.162921)
							(end -0.1524 0.127)
						)
						(arc
							(start -0.1524 -0.127)
							(mid -0.137521 -0.162921)
							(end -0.1016 -0.1778)
						)
						(arc
							(start 0.1016 -0.1778)
							(mid 0.137521 -0.162921)
							(end 0.1524 -0.127)
						)
					)
					(width 0)
					(fill yes)
				)
			)
		)
		(pad "2" smd custom
			(at 0 0.2794 270)
			(size 0.0762 0.0762)
			(layers "B.Cu" "B.Mask" "B.Paste")
			(net "GND")
			(options
				(clearance outline)
				(anchor circle)
			)
			(primitives
				(gr_poly
					(pts
						(arc
							(start 0.1524 0.127)
							(mid 0.137521 0.162921)
							(end 0.1016 0.1778)
						)
						(arc
							(start -0.1016 0.1778)
							(mid -0.137521 0.162921)
							(end -0.1524 0.127)
						)
						(arc
							(start -0.1524 -0.127)
							(mid -0.137521 -0.162921)
							(end -0.1016 -0.1778)
						)
						(arc
							(start 0.1016 -0.1778)
							(mid 0.137521 -0.162921)
							(end 0.1524 -0.127)
						)
					)
					(width 0)
					(fill yes)
				)
			)
		)
	)
	(footprint ""
		(layer "B.Cu")
		(at 194.0814 -66.6115 90)
		(property "Reference" "C424"
			(at 0 0 90)
			(layer "B.SilkS")
			(hide yes)
			(effects
				(font
					(size 1.27 1.27)
				)
				(justify mirror)
			)
		)
		(property "Value" "SC1KP50V2KX-1GP"
			(at -1.1811 -2.7051 90)
			(unlocked yes)
			(layer "B.Fab")
			(hide yes)
			(effects
				(font
					(size 1.016 1.016)
					(thickness 0.1524)
				)
				(justify mirror)
			)
		)
		(property "Device Type" "C402H22"
			(at -1.1811 -4.2291 90)
			(unlocked yes)
			(layer "B.Fab")
			(hide yes)
			(effects
				(font
					(size 1.016 1.016)
					(thickness 0.1524)
				)
				(justify mirror)
			)
		)
		(duplicate_pad_numbers_are_jumpers no)
		(fp_rect
			(start 0.4318 0.9525)
			(end -0.4318 -0.9525)
			(stroke
				(width 0)
				(type default)
			)
			(fill no)
			(layer "B.CrtYd")
		)
		(fp_rect
			(start 0.4318 0.9525)
			(end -0.4318 -0.9525)
			(stroke
				(width 0)
				(type default)
			)
			(fill no)
			(layer "B.Fab")
		)
		(pad "1" smd custom
			(at 0 -0.4445 270)
			(size 0.1524 0.1524)
			(layers "B.Cu" "B.Mask" "B.Paste")
			(net "P0V975")
			(options
				(clearance outline)
				(anchor circle)
			)
			(primitives
				(gr_poly
					(pts
						(arc
							(start 0.3048 0.2032)
							(mid 0.275042 0.275042)
							(end 0.2032 0.3048)
						)
						(arc
							(start -0.2032 0.3048)
							(mid -0.275042 0.275042)
							(end -0.3048 0.2032)
						)
						(arc
							(start -0.3048 -0.2032)
							(mid -0.275042 -0.275042)
							(end -0.2032 -0.3048)
						)
						(arc
							(start 0.2032 -0.3048)
							(mid 0.275042 -0.275042)
							(end 0.3048 -0.2032)
						)
					)
					(width 0)
					(fill yes)
				)
			)
		)
		(pad "2" smd custom
			(at 0 0.4445 270)
			(size 0.1524 0.1524)
			(layers "B.Cu" "B.Mask" "B.Paste")
			(net "GND")
			(options
				(clearance outline)
				(anchor circle)
			)
			(primitives
				(gr_poly
					(pts
						(arc
							(start 0.3048 0.2032)
							(mid 0.275042 0.275042)
							(end 0.2032 0.3048)
						)
						(arc
							(start -0.2032 0.3048)
							(mid -0.275042 0.275042)
							(end -0.3048 0.2032)
						)
						(arc
							(start -0.3048 -0.2032)
							(mid -0.275042 -0.275042)
							(end -0.2032 -0.3048)
						)
						(arc
							(start 0.2032 -0.3048)
							(mid 0.275042 -0.275042)
							(end 0.3048 -0.2032)
						)
					)
					(width 0)
					(fill yes)
				)
			)
		)
	)
	(footprint ""
		(layer "B.Cu")
		(at 206.40802 -63.304166 -90)
		(property "Reference" "TP129"
			(at 0 0 90)
			(layer "B.SilkS")
			(hide yes)
			(effects
				(font
					(size 1.27 1.27)
				)
				(justify mirror)
			)
		)
		(property "Value" "TPAD28-2-GP"
			(at 0.0127 -1.6637 270)
			(unlocked yes)
			(layer "B.Fab")
			(hide yes)
			(effects
				(font
					(size 1.016 1.016)
					(thickness 0.1524)
				)
				(justify mirror)
			)
		)
		(property "Device Type" "TPAD28"
			(at 0.0127 -3.1877 270)
			(unlocked yes)
			(layer "B.Fab")
			(hide yes)
			(effects
				(font
					(size 1.016 1.016)
					(thickness 0.1524)
				)
				(justify mirror)
			)
		)
		(duplicate_pad_numbers_are_jumpers no)
		(fp_poly
			(pts
				(arc
					(start 0 -0.3556)
					(mid 0 0.3556)
					(end 0 -0.3556)
				)
			)
			(stroke
				(width 0)
				(type default)
			)
			(fill no)
			(layer "B.CrtYd")
		)
		(fp_poly
			(pts
				(arc
					(start 0 -0.6096)
					(mid 0 0.6096)
					(end 0 -0.6096)
				)
			)
			(stroke
				(width 0)
				(type default)
			)
			(fill no)
			(layer "B.Fab")
		)
		(pad "1" smd circle
			(at 0 0 90)
			(size 0.7112 0.7112)
			(layers "B.Cu" "B.Mask" "B.Paste")
			(net "IOC_SIO_BLINK")
		)
	)
	(footprint ""
		(layer "B.Cu")
		(at 60.793884 -158.261304 180)
		(property "Reference" "L4"
			(at 0 0 0)
			(layer "B.SilkS")
			(hide yes)
			(effects
				(font
					(size 1.27 1.27)
				)
				(justify mirror)
			)
		)
		(property "Value" "MMZ2012S601ATA1N-GP"
			(at 0 -4.2418 180)
			(unlocked yes)
			(layer "B.Fab")
			(hide yes)
			(effects
				(font
					(size 1.016 1.016)
					(thickness 0.1524)
				)
				(justify mirror)
			)
		)
		(property "Device Type" "L805H42"
			(at 0 -5.7912 180)
			(unlocked yes)
			(layer "B.Fab")
			(hide yes)
			(effects
				(font
					(size 1.016 1.016)
					(thickness 0.1524)
				)
				(justify mirror)
			)
		)
		(duplicate_pad_numbers_are_jumpers no)
		(fp_line
			(start 0.889 1.7018)
			(end 0.889 -1.7018)
			(stroke
				(width 0.1524)
				(type default)
			)
			(layer "B.SilkS")
		)
		(fp_line
			(start 0.889 -1.7018)
			(end -0.889 -1.7018)
			(stroke
				(width 0.1524)
				(type default)
			)
			(layer "B.SilkS")
		)
		(fp_line
			(start -0.889 1.7018)
			(end 0.889 1.7018)
			(stroke
				(width 0.1524)
				(type default)
			)
			(layer "B.SilkS")
		)
		(fp_line
			(start -0.889 -1.7018)
			(end -0.889 1.7018)
			(stroke
				(width 0.1524)
				(type default)
			)
			(layer "B.SilkS")
		)
		(fp_rect
			(start 0.9652 1.778)
			(end -0.9652 -1.778)
			(stroke
				(width 0)
				(type default)
			)
			(fill no)
			(layer "B.CrtYd")
		)
		(fp_rect
			(start 0.9652 1.778)
			(end -0.9652 -1.778)
			(stroke
				(width 0)
				(type default)
			)
			(fill no)
			(layer "B.Fab")
		)
		(pad "1" smd rect
			(at 0 -0.9652)
			(size 1.397 1.143)
			(layers "B.Cu" "B.Mask" "B.Paste")
			(net "P3V3_STBY")
		)
		(pad "2" smd rect
			(at 0 0.9652)
			(size 1.397 1.143)
			(layers "B.Cu" "B.Mask" "B.Paste")
			(net "VPLLAV33")
		)
	)
	(footprint ""
		(layer "B.Cu")
		(at 96.52 -152.4254 180)
		(property "Reference" "R42"
			(at 0 0 0)
			(layer "B.SilkS")
			(hide yes)
			(effects
				(font
					(size 1.27 1.27)
				)
				(justify mirror)
			)
		)
		(property "Value" "4K7R2F-GP"
			(at -0.064008 -3.993896 180)
			(unlocked yes)
			(layer "B.Fab")
			(hide yes)
			(effects
				(font
					(size 1.016 1.016)
					(thickness 0.1524)
				)
				(justify mirror)
			)
		)
		(property "Device Type" "R402H16"
			(at -0.064008 -5.517896 180)
			(unlocked yes)
			(layer "B.Fab")
			(hide yes)
			(effects
				(font
					(size 1.016 1.016)
					(thickness 0.1524)
				)
				(justify mirror)
			)
		)
		(duplicate_pad_numbers_are_jumpers no)
		(fp_line
			(start 0.508 -0.9398)
			(end 0.508 0.9398)
			(stroke
				(width 0.1524)
				(type default)
			)
			(layer "B.SilkS")
		)
		(fp_line
			(start -0.508 -0.9398)
			(end 0.508 -0.9398)
			(stroke
				(width 0.1524)
				(type default)
			)
			(layer "B.SilkS")
		)
		(fp_rect
			(start 0.508 0.9398)
			(end -0.508 -0.9398)
			(stroke
				(width 0)
				(type default)
			)
			(fill no)
			(layer "B.CrtYd")
		)
		(fp_rect
			(start 0.508 0.9398)
			(end -0.508 -0.9398)
			(stroke
				(width 0)
				(type default)
			)
			(fill no)
			(layer "B.Fab")
		)
		(pad "1" smd custom
			(at 0 -0.4445)
			(size 0.1397 0.1397)
			(layers "B.Cu" "B.Mask" "B.Paste")
			(net "USB_EN_3")
			(options
				(clearance outline)
				(anchor circle)
			)
			(primitives
				(gr_poly
					(pts
						(arc
							(start -0.1778 0.2794)
							(mid -0.249642 0.249642)
							(end -0.2794 0.1778)
						)
						(arc
							(start -0.2794 -0.1778)
							(mid -0.249642 -0.249642)
							(end -0.1778 -0.2794)
						)
						(arc
							(start 0.1778 -0.2794)
							(mid 0.249642 -0.249642)
							(end 0.2794 -0.1778)
						)
						(arc
							(start 0.2794 0.1778)
							(mid 0.249642 0.249642)
							(end 0.1778 0.2794)
						)
					)
					(width 0)
					(fill yes)
				)
			)
		)
		(pad "2" smd custom
			(at 0 0.4445)
			(size 0.1397 0.1397)
			(layers "B.Cu" "B.Mask" "B.Paste")
			(net "GND")
			(options
				(clearance outline)
				(anchor circle)
			)
			(primitives
				(gr_poly
					(pts
						(arc
							(start -0.1778 0.2794)
							(mid -0.249642 0.249642)
							(end -0.2794 0.1778)
						)
						(arc
							(start -0.2794 -0.1778)
							(mid -0.249642 -0.249642)
							(end -0.1778 -0.2794)
						)
						(arc
							(start 0.1778 -0.2794)
							(mid 0.249642 -0.249642)
							(end 0.2794 -0.1778)
						)
						(arc
							(start 0.2794 0.1778)
							(mid 0.249642 0.249642)
							(end 0.1778 0.2794)
						)
					)
					(width 0)
					(fill yes)
				)
			)
		)
	)
)
